FILE_TYPE = CONNECTIVITY;
{Allegro Design Entry HDL 16.6-p007 (v16-6-112F) 10/10/2012}
"PAGE_NUMBER" = 226;
0"NC";
1"P3V3_STBY\g";
2"GND\g";
3"GND\g";
4"GND\g";
5"P3V3_STBY\g";
6"GND\g";
7"GND\g";
8"GND\g";
9"GND\g";
10"GND\g";
11"GND\g";
12"PVCCIO_CPU1\g";
13"VR_FET_SW_P12V_STBY_PVDDQ_KLM\g";
14"GND\g";
15"GND\g";
16"PVCCIO_CPU1\g";
17"GND\g";
18"GND\g";
19"VR_PVDDQ_KLM_VINSEN";
20"VR_PVDDQ_KLM_VD12";
21"VR_PVDDQ_KLM_AIREF2";
22"VR_PVDDQ_KLM_AIREF1";
23"FM_PVDDQ_KLM_EN";
24"VR_PVDDQ_KLM_VREN";
25"IRQ_PVDDQ_KLM_VRHOT_LVT3_R_N";
26"IRQ_PVDDQ_KLM_VRHOT_LVT3_N";
27"SVID_CLK1_CPU1_R";
28"SVID_CLK_PVDDQ_KLM";
29"VSENSE_PVDDQ_KLM_P";
30"VR_PVDDQ_KLM_AVSP";
31"SVID_VDIO_PVDDQ_KLM";
32"SVID_DIO1_CPU1_R";
33"SMB_VR_SDA_VDDQ_KLM";
34"SMB_VR_STBY_LVC3_SDA";
35"SMB_VR_SCL_VDDQ_KLM";
36"SMB_VR_STBY_LVC3_SCL";
37"SVID_ALERT_PVDDQ_KLM";
38"SVID_ALERT1_CPU1_R_N";
39"PWRGD_PVDDQ_KLM_R";
40"PWRGD_PVDDQ_KLM";
41"VR_PVDDQ_KLM_VD12";
42"PU_VR_PVDDQ_KLM_FAULT1";
43"NC_PVDDQ_KLM_GP0";
44"TP_PVDDQ_KLM_BPWM1";
45"NC_PVDDQ_KLM_PWM3";
46"NC_PVDDQ_KLM_DNC0";
47"NC_PVDDQ_KLM_DNC1";
48"NC_PVDDQ_KLM_PINALRT_N";
49"NC_PVDDQ_KLM_GP1";
50"VR_PVDDQ_KLM_VD12";
51"VR_PVDDQ_KLM_PWM1";
52"VR_PVDDQ_KLM_PWM2";
53"VR_PVDDQ_KLM_VDD";
54"TP_PVDDQ_KLM_PH3_IMON_REF";
55"A_TSENSE_PVDDQ_KLM";
56"TP_PVDDQ_KLM_BVREF";
57"TP_PVDDQ_KLM_RESET_N";
58"TP_PVDDQ_KLM_PH3_IMON";
59"TP_PVDDQ_KLM_BTSEN";
60"TP_PVDDQ_KLM_BREF1";
61"TP_PVDDQ_KLM_BVSEN";
62"VR_PVDDQ_KLM_XADDR2";
63"VR_PVDDQ_KLM_XADDR1";
64"VSENSE_PVDDQ_KLM_N";
65"VR_PVDDQ_KLM_AIINSEN";
66"ISENSE_PVDDQ_KLM_PH1_IMON";
67"ISENSE_PVDDQ_KLM_PH2_IMON";
68"VR_PVDDQ_KLM_VINSEN";
%"RES"
"2","(2750,3050)","0","mstr_discrete","I13";
;
CDS_SEC"1"
ROOM"VDDQ_KLM_PWR_VR"
CDS_LIB"mstr_discrete"
CDS_LOCATION"R1B13"
SEC"1"
SEC_TYPE"0402"
WATTAGE"1/16W"
PACK_TYPE"0402"
MATERIAL"EMPTY"
TOLERANCE"1.0%"
VALUE"2.26K"
LOCATION"R1B13"
PART_NUMBER"G21796-311";
"A"
$PN"1"1;
"B"
$PN"2"42;
%"RES"
"1","(3375,2525)","0","mstr_discrete","I14";
;
CDS_SEC"1"
SEC_TYPE"0402"
SEC"1"
CDS_LOCATION"R1B5"
ROOM"VDDQ_KLM_PWR_VR"
CDS_LIB"mstr_discrete"
PART_NUMBER"G21796-250"
TOLERANCE"1.0%"
PACK_TYPE"0402"
LOCATION"R1B5"
VALUE"22.1"
MATERIAL"CHIP"
WATTAGE"1/16W";
"B"
$PN"2"40;
"A"
$PN"1"39;
%"P3V3_STBY"
"1","(2450,3700)","0","mstr_symbols","I15";
;
CDS_LIB"mstr_symbols"
SIZE"1B"
VOLTAGE"3.3V"
BODY_TYPE"PLUMBING"
HDL_POWER"P3V3_STBY";
"G\NAC"1;
%"RES"
"1","(2575,2375)","0","mstr_discrete","I16";
;
CDS_SEC"1"
CDS_LOCATION"R1B11"
CDS_LIB"mstr_discrete"
SEC"1"
SEC_TYPE"0402"
ROOM"VDDQ_KLM_PWR_VR"
MATERIAL"CHIP"
TOLERANCE"5%"
LOCATION"R1B11"
PACK_TYPE"0402"
PART_NUMBER"G21497-005"
VALUE"0.0"
WATTAGE"1/16W";
"B"
$PN"2"38;
"A"
$PN"1"37;
%"RES"
"2","(2350,3025)","0","mstr_discrete","I17";
;
CDS_SEC"1"
CDS_LIB"mstr_discrete"
ROOM"VDDQ_KLM_PWR_VR"
SEC"1"
CDS_LOCATION"R1B2"
SEC_TYPE"0402"
PACK_TYPE"0402"
MATERIAL"CHIP"
WATTAGE"1/16W"
PART_NUMBER"G21796-026"
TOLERANCE"1%"
LOCATION"R1B2"
VALUE"1.00K";
"A"
$PN"1"1;
"B"
$PN"2"39;
%"RES"
"1","(3100,2025)","0","mstr_discrete","I21";
;
CDS_LOCATION"R1B6"
$SEC"1"
CDS_SEC"1"
ROOM"VDDQ_KLM_PWR_VR"
CDS_LIB"mstr_discrete"
LOCATION"R1B6"
PART_NUMBER"G21796-173"
TOLERANCE"1%"
PACK_TYPE"0402"
MATERIAL"CHIP"
VALUE"20.0"
WATTAGE"1/16W";
"B"
$PN"2"36;
"A"
$PN"1"35;
%"RES"
"1","(2775,1975)","0","mstr_discrete","I22";
;
CDS_SEC"1"
$SEC"1"
ROOM"VDDQ_KLM_PWR_VR"
CDS_LOCATION"R1B7"
CDS_LIB"mstr_discrete"
PART_NUMBER"G21796-173"
LOCATION"R1B7"
TOLERANCE"1%"
PACK_TYPE"0402"
MATERIAL"CHIP"
WATTAGE"1/16W"
VALUE"20.0";
"B"
$PN"2"34;
"A"
$PN"1"33;
%"RES"
"1","(2775,1675)","0","mstr_discrete","I23";
;
CDS_SEC"1"
SEC"1"
SEC_TYPE"0402"
ROOM"VDDQ_KLM_PWR_VR"
CDS_LIB"mstr_discrete"
CDS_LOCATION"R1B10"
PACK_TYPE"0402"
LOCATION"R1B10"
PART_NUMBER"G21497-005"
VALUE"0.0"
TOLERANCE"5%"
MATERIAL"CHIP"
WATTAGE"1/16W";
"B"
$PN"2"32;
"A"
$PN"1"31;
%"GND"
"1","(2000,800)","0","mstr_symbols","I24";
;
ROOM"VDDQ_KLM_PWR_VR"
CDS_LIB"mstr_symbols"
VOLTAGE"0"
SIZE"1B"
BODY_TYPE"PLUMBING"
HDL_POWER"GND";
"A\NAC"2;
%"CAP_A"
"1","(1525,3075)","0","dev_discrete","I25";
;
CDS_LIB"dev_discrete"
ROOM"VDDQ_KLM_PWR_VR"
$SEC"1"
CDS_SEC"1"
CDS_LOCATION"C1B6"
MATERIAL"X6S"
PACK_TYPE"0402V"
TOLERANCE"10%"
PART_NUMBER"D97712-004"
VOLTAGE"6.3V"
VALUE"1.0UF"
LOCATION"C1B6";
"B"
$PN"2"3;
"A"
$PN"1"53;
%"GND"
"1","(1525,2875)","0","mstr_symbols","I26";
;
ROOM"VDDQ_KLM_PWR_VR"
CDS_LIB"mstr_symbols"
VOLTAGE"0"
SIZE"1B"
BODY_TYPE"PLUMBING"
HDL_POWER"GND";
"A\NAC"3;
%"CAP_A"
"1","(1125,3075)","0","dev_discrete","I27";
;
CDS_LIB"dev_discrete"
CDS_SEC"1"
ROOM"VDDQ_KLM_PWR_VR"
CDS_LOCATION"C1B5"
SEC"1"
SEC_TYPE"0402V"
MATERIAL"X7R"
TOLERANCE"10%"
PACK_TYPE"0402V"
PART_NUMBER"A36096-030"
VOLTAGE"16V"
VALUE"0.1UF"
LOCATION"C1B5";
"B"
$PN"2"4;
"A"
$PN"1"53;
%"GND"
"1","(1125,2875)","0","mstr_symbols","I28";
;
ROOM"VDDQ_KLM_PWR_VR"
VOLTAGE"0"
CDS_LIB"mstr_symbols"
SIZE"1B"
BODY_TYPE"PLUMBING"
HDL_POWER"GND";
"A\NAC"4;
%"P3V3_STBY"
"1","(500,3950)","0","mstr_symbols","I29";
;
CDS_LIB"mstr_symbols"
VOLTAGE"3.3V"
SIZE"1B"
BODY_TYPE"PLUMBING"
HDL_POWER"P3V3_STBY";
"G\NAC"5;
%"RES"
"2","(825,3525)","0","mstr_discrete","I30";
;
CDS_SEC"1"
CDS_LIB"mstr_discrete"
ROOM"VDDQ_KLM_PWR_VR"
CDS_LOCATION"R9M3"
SEC_TYPE"0402"
SEC"1"
TOLERANCE"5%"
PACK_TYPE"0402"
MATERIAL"CHIP"
WATTAGE"1/16W"
LOCATION"R9M3"
VALUE"0.0"
PART_NUMBER"G21497-005";
"A"
$PN"1"5;
"B"
$PN"2"53;
%"RES"
"1","(-1675,1175)","0","mstr_discrete","I32";
;
CDS_SEC"1"
NO_XNET_CONNECTION"1"
SEC"1"
SEC_TYPE"0402"
ROOM"VDDQ_KLM_PWR_VR"
CDS_LOCATION"R1B16"
CDS_LIB"mstr_discrete"
PART_NUMBER"G21796-066"
PACK_TYPE"0402"
MATERIAL"CHIP"
LOCATION"R1B16"
TOLERANCE"1%"
VALUE"10.0"
WATTAGE"1/16W";
"B"
$PN"2"30;
"A"
$PN"1"29;
%"GND"
"1","(100,825)","0","mstr_symbols","I35";
;
ROOM"VDDQ_KLM_PWR_VR"
VOLTAGE"0"
CDS_LIB"mstr_symbols"
SIZE"1B"
BODY_TYPE"PLUMBING"
HDL_POWER"GND";
"A\NAC"6;
%"CAP"
"1","(25,725)","2","mstr_discrete","I36";
;
CDS_SEC"1"
SEC_TYPE"0402LF"
SEC"1"
CDS_LOCATION"C1B11"
ROOM"VDDQ_KLM_PWR_VR"
CDS_LIB"mstr_discrete"
TOLERANCE"10%"
PART_NUMBER"A36096-050"
LOCATION"C1B11"
VALUE"220PF"
PACK_TYPE"0402LF"
VOLTAGE"50V"
MATERIAL"X7R";
"A"
$PN"1"55;
"B"
$PN"2"11;
%"CAP"
"1","(-1500,1025)","0","mstr_discrete","I39";
;
CDS_SEC"1"
CDS_LIB"mstr_discrete"
CDS_LOCATION"C1B12"
SEC"1"
NO_XNET_CONNECTION"1"
ROOM"VDDQ_KLM_PWR_VR"
SEC_TYPE"0402LF"
PACK_TYPE"0402LF"
PART_NUMBER"A36096-050"
LOCATION"C1B12"
VALUE"220PF"
VOLTAGE"50V"
MATERIAL"X7R"
TOLERANCE"10%";
"A"
$PN"1"30;
"B"
$PN"2"64;
%"CAP_A"
"1","(3750,150)","0","dev_discrete","I41";
;
CDS_LIB"dev_discrete"
CDS_LOCATION"C1B3"
CDS_SEC"1"
SEC_TYPE"0402V"
SEC"1"
ROOM"VDDQ_KLM_PWR_VR"
PACK_TYPE"0402V"
PART_NUMBER"D97712-004"
MATERIAL"X6S"
VOLTAGE"6.3V"
TOLERANCE"10%"
VALUE"1.0UF"
LOCATION"C1B3";
"B"
$PN"2"7;
"A"
$PN"1"41;
%"GND"
"1","(3750,-175)","0","mstr_symbols","I42";
;
ROOM"VDDQ_KLM_PWR_VR"
CDS_LIB"mstr_symbols"
SIZE"1B"
VOLTAGE"0"
BODY_TYPE"PLUMBING"
HDL_POWER"GND";
"A\NAC"7;
%"GND"
"1","(3350,-25)","0","mstr_symbols","I43";
;
SIZE"1B"
CDS_LIB"mstr_symbols"
VOLTAGE"0"
ROOM"VDDQ_KLM_PWR_VR"
BODY_TYPE"PLUMBING"
HDL_POWER"GND";
"A\NAC"8;
%"CAP_A"
"1","(3350,175)","0","dev_discrete","I44";
;
CDS_LIB"dev_discrete"
ROOM"VDDQ_KLM_PWR_VR"
CDS_LOCATION"C1B2"
CDS_SEC"1"
SEC_TYPE"0402V"
SEC"1"
PACK_TYPE"0402V"
MATERIAL"X7R"
VOLTAGE"16V"
TOLERANCE"10%"
VALUE"0.1UF"
LOCATION"C1B2"
PART_NUMBER"A36096-030";
"B"
$PN"2"8;
"A"
$PN"1"41;
%"GND"
"1","(575,25)","0","mstr_symbols","I46";
;
ROOM"VDDQ_KLM_PWR_VR"
SIZE"1B"
VOLTAGE"0"
CDS_LIB"mstr_symbols"
BODY_TYPE"PLUMBING"
HDL_POWER"GND";
"A\NAC"9;
%"GND"
"1","(200,25)","0","mstr_symbols","I47";
;
ROOM"VDDQ_KLM_PWR_VR"
SIZE"1B"
VOLTAGE"0"
CDS_LIB"mstr_symbols"
BODY_TYPE"PLUMBING"
HDL_POWER"GND";
"A\NAC"10;
%"GND"
"1","(25,25)","0","mstr_symbols","I48";
;
ROOM"VDDQ_KLM_PWR_VR"
SIZE"1B"
CDS_LIB"mstr_symbols"
VOLTAGE"0"
BODY_TYPE"PLUMBING"
HDL_POWER"GND";
"A\NAC"11;
%"PVCCIO_CPU1"
"1","(-675,3900)","0","mstr_symbols","I49";
;
CDS_LIB"mstr_symbols"
VOLTAGE"1.1V"
BODY_TYPE"PLUMBING"
HDL_POWER"PVCCIO_CPU1";
"G\NAC"12;
%"RES"
"2","(-675,3550)","0","mstr_discrete","I50";
;
CDS_SEC"1"
MATERIAL"CHIP"
CDS_LIB"mstr_discrete"
ROOM"VDDQ_KLM_PWR_VR"
CDS_LOCATION"R9M6"
SEC"1"
SEC_TYPE"0402"
PACK_TYPE"0402"
TOLERANCE"1%"
VALUE"49.9"
LOCATION"R9M6"
WATTAGE"1/16W"
PART_NUMBER"G21796-047";
"A"
$PN"1"12;
"B"
$PN"2"27;
%"RES"
"1","(-300,3050)","0","mstr_discrete","I53";
;
CDS_SEC"1"
CDS_LOCATION"R1B8"
ROOM"VDDQ_KLM_PWR_VR"
SEC"1"
SEC_TYPE"0402"
CDS_LIB"mstr_discrete"
TOLERANCE"1%"
PACK_TYPE"0402"
MATERIAL"CHIP"
WATTAGE"1/16W"
PART_NUMBER"G21796-009"
LOCATION"R1B8"
VALUE"150.0";
"B"
$PN"2"28;
"A"
$PN"1"27;
%"VCC_CORE"
"1","(-1250,3975)","0","mstr_symbols","I56";
;
CDS_LIB"mstr_symbols"
HDL_POWER"VR_FET_SW_P12V_STBY_PVDDQ_KLM";
"A"13;
%"RES"
"2","(-1250,3725)","0","mstr_discrete","I57";
;
CDS_SEC"1"
CDS_LIB"mstr_discrete"
ROOM"VDDQ_KLM_PWR_VR"
CDS_LOCATION"R9M8"
SEC"1"
SEC_TYPE"0402"
PACK_TYPE"0402"
TOLERANCE"1%"
MATERIAL"CHIP"
WATTAGE"1/16W"
VALUE"100.0K"
LOCATION"R9M8"
PART_NUMBER"G21796-160";
"A"
$PN"1"13;
"B"
$PN"2"19;
%"RES"
"2","(-1250,3325)","0","mstr_discrete","I58";
;
CDS_SEC"1"
CDS_LIB"mstr_discrete"
CDS_LOCATION"R1B9"
ROOM"VDDQ_KLM_PWR_VR"
SEC"1"
SEC_TYPE"0402"
WATTAGE"1/16W"
MATERIAL"CHIP"
PACK_TYPE"0402"
LOCATION"R1B9"
VALUE"1.5K"
TOLERANCE"1%"
PART_NUMBER"G21796-003";
"A"
$PN"1"19;
"B"
$PN"2"14;
%"CAP"
"1","(-1475,3375)","2","mstr_discrete","I59";
;
CDS_SEC"1"
CDS_LIB"mstr_discrete"
ROOM"VDDQ_KLM_PWR_VR"
CDS_LOCATION"C1B8"
SEC"1"
SEC_TYPE"0402LF"
MATERIAL"X7R"
VOLTAGE"50V"
PACK_TYPE"0402LF"
TOLERANCE"10%"
VALUE"1000PF"
PART_NUMBER"A36096-046"
LOCATION"C1B8";
"A"
$PN"1"19;
"B"
$PN"2"15;
%"GND"
"1","(-1250,3100)","0","mstr_symbols","I60";
;
SIZE"1B"
ROOM"VDDQ_KLM_PWR_VR"
CDS_LIB"mstr_symbols"
VOLTAGE"0"
BODY_TYPE"PLUMBING"
HDL_POWER"GND";
"A\NAC"14;
%"GND"
"1","(-1475,3150)","0","mstr_symbols","I61";
;
ROOM"VDDQ_KLM_PWR_VR"
VOLTAGE"0"
CDS_LIB"mstr_symbols"
SIZE"1B"
BODY_TYPE"PLUMBING"
HDL_POWER"GND";
"A\NAC"15;
%"PVCCIO_CPU1"
"1","(3800,3000)","0","mstr_symbols","I7";
;
CDS_LIB"mstr_symbols"
VOLTAGE"1.1V"
BODY_TYPE"PLUMBING"
HDL_POWER"PVCCIO_CPU1";
"G\NAC"16;
%"RES"
"2","(575,275)","0","mstr_discrete","I77";
;
CDS_LOCATION"R1B15"
CDS_LIB"mstr_discrete"
ROOM"VDDQ_KLM_PWR_VR"
$SEC"1"
CDS_SEC"1"
PACK_TYPE"0402"
MATERIAL"CHIP"
WATTAGE"1/16W"
TOLERANCE"1.0%"
VALUE"5.36K"
LOCATION"R1B15"
PART_NUMBER"G21796-297";
"A"
$PN"1"62;
"B"
$PN"2"9;
%"RES"
"2","(200,275)","0","mstr_discrete","I78";
;
CDS_LOCATION"R1B12"
CDS_LIB"mstr_discrete"
ROOM"VDDQ_KLM_PWR_VR"
$SEC"1"
CDS_SEC"1"
WATTAGE"1/16W"
MATERIAL"CHIP"
PACK_TYPE"0402"
TOLERANCE"1%"
VALUE"3.16K"
LOCATION"R1B12"
PART_NUMBER"G21796-043";
"A"
$PN"1"63;
"B"
$PN"2"10;
%"RES"
"2","(2075,3025)","0","mstr_discrete","I79";
;
CDS_SEC"1"
CDS_LIB"mstr_discrete"
ROOM"RQ_PVDDQ_KLM_VRHOT_LVT3_N"
CDS_LOCATION"R1B1"
SEC"1"
SEC_TYPE"0402"
WATTAGE"1/16W"
MATERIAL"CHIP"
PACK_TYPE"0402"
PART_NUMBER"G21796-026"
TOLERANCE"1%"
LOCATION"R1B1"
VALUE"1.00K";
"A"
$PN"1"1;
"B"
$PN"2"25;
%"RES"
"2","(3800,2775)","0","mstr_discrete","I8";
;
CDS_SEC"1"
CDS_LIB"mstr_discrete"
ROOM"VDDQ_KLM_PWR_VR"
CDS_LOCATION"R9M7"
SEC"1"
SEC_TYPE"0402"
WATTAGE"1/16W"
PACK_TYPE"0402"
MATERIAL"EMPTY"
TOLERANCE"1%"
VALUE"100.0"
LOCATION"R9M7"
PART_NUMBER"G21796-017";
"A"
$PN"1"16;
"B"
$PN"2"32;
%"CAP"
"1","(2900,975)","0","mstr_discrete","I80";
;
CDS_SEC"1"
CDS_LIB"mstr_discrete"
ROOM"VDDQ_KLM_PWR_VR"
CDS_LOCATION"C1B4"
SEC"1"
SEC_TYPE"0402LF"
MATERIAL"X7R"
VOLTAGE"50V"
TOLERANCE"10%"
LOCATION"C1B4"
PACK_TYPE"0402LF"
VALUE"1000PF"
PART_NUMBER"A36096-046";
"A"
$PN"1"39;
"B"
$PN"2"17;
%"GND"
"1","(2900,700)","0","mstr_symbols","I81";
;
ROOM"VDDQ_KLM_PWR_VR"
VOLTAGE"0"
CDS_LIB"mstr_symbols"
SIZE"1B"
BODY_TYPE"PLUMBING"
HDL_POWER"GND";
"A\NAC"17;
%"RES"
"1","(3275,2425)","0","mstr_discrete","I82";
;
CDS_SEC"1"
SEC_TYPE"0402"
SEC"1"
CDS_LIB"mstr_discrete"
CDS_LOCATION"R1B4"
PACK_TYPE"0402"
LOCATION"R1B4"
PART_NUMBER"G21796-074"
TOLERANCE"1%"
MATERIAL"CHIP"
VALUE"33.2"
WATTAGE"1/16W";
"B"
$PN"2"26;
"A"
$PN"1"25;
%"RES"
"1","(-1550,1475)","0","mstr_discrete","I84";
;
CDS_SEC"1"
$SEC"1"
ROOM"PVCCIN_CPU0_VR"
CDS_LOCATION"R9M9"
CDS_LIB"mstr_discrete"
PACK_TYPE"0402"
LOCATION"R9M9"
PART_NUMBER"G21497-005"
MATERIAL"CHIP"
TOLERANCE"5%"
WATTAGE"1/16W"
VALUE"0.0";
"B"
$PN"2"24;
"A"
$PN"1"23;
%"RES"
"2","(75,3550)","0","mstr_discrete","I85";
;
CDS_SEC"1"
CDS_LIB"mstr_discrete"
CDS_LOCATION"R9M5"
ROOM"BMC"
SEC"1"
SEC_TYPE"0402"
BOM_COST"SM_CONTROLLER"
PACK_TYPE"0402"
WATTAGE"1/16W"
PART_NUMBER"G21796-010"
MATERIAL"EMPTY"
TOLERANCE"1%"
LOCATION"R9M5"
VALUE"100.0K";
"A"
$PN"1"5;
"B"
$PN"2"24;
%"RES"
"1","(-1625,2725)","0","mstr_discrete","I87";
;
CDS_SEC"1"
$SEC"1"
ROOM"PVCCIN_CPU0_VR"
CDS_LIB"mstr_discrete"
CDS_LOCATION"R9M11"
LOCATION"R9M11"
PART_NUMBER"G21497-005"
PACK_TYPE"0402"
MATERIAL"CHIP"
TOLERANCE"5%"
VALUE"0.0"
WATTAGE"1/16W";
"B"
$PN"2"22;
"A"
$PN"1"20;
%"RES"
"1","(-825,2875)","0","mstr_discrete","I88";
;
CDS_SEC"1"
$SEC"1"
CDS_LIB"mstr_discrete"
CDS_LOCATION"R9M10"
ROOM"PVCCIN_CPU0_VR"
PACK_TYPE"0402"
LOCATION"R9M10"
PART_NUMBER"G21497-005"
MATERIAL"CHIP"
VALUE"0.0"
TOLERANCE"5%"
WATTAGE"1/16W";
"B"
$PN"2"21;
"A"
$PN"1"20;
%"PXM1310B"
"2","(1425,1775)","0","mstr_controller","I90";
;
CDS_SEC"1"
CDS_LMAN_SYM_OUTLINE"-400,900,400,-900"
CDS_LIB"mstr_controller"
CDS_LOCATION"EU1B1"
PACK_TYPE"QFN"
SEC_TYPE"QFN"
SEC"1"
PART_NUMBER"H89186-001"
LOCATION"EU1B1"
MATERIAL"IC";
"MP2"
$PN"18"43;
"MP1"
$PN"14"49;
"MP0"
$PN"13"42;
"AVREN"
$PN"10"24;
"AVRRDY"
$PN"9"39;
"IINSEN"
$PN"38"65;
"GND"
$PN"27"2;
"VD12"
$PN"40"50;
"VINSEN"
$PN"37"68;
"BVREF"
$PN"30"56;
"BVSEN"
$PN"29"61;
"AVREF"
$PN"20"64;
"AVSEN"
$PN"19"30;
"VALRT_N \B"
$PN"17"37;
"PINALRT_N \B"
$PN"12"48;
"VRHOT_N \B"
$PN"11"25;
"DNC<1>"
$PN"28"47;
"DNC<0>"
$PN"2"46;
"BIREF1"
$PN"31"60;
"BISEN1"
$PN"32"6;
"BTSEN"
$PN"34"59;
"VDD"
$PN"39"53;
"AIREF1"
$PN"21"22;
"AISEN1"
$PN"22"66;
"ATSEN"
$PN"35"55;
"AIREF2"
$PN"23"21;
"AISEN2"
$PN"24"67;
"XADDR2"
$PN"33"62;
"AIREF3"
$PN"25"54;
"AISEN3"
$PN"26"58;
"XADDR1"
$PN"36"63;
"RESET_N \B"
$PN"8"57;
"VDIO"
$PN"16"31;
"VCLK"
$PN"15"28;
"SCL"
$PN"7"35;
"SDA"
$PN"6"33;
"APWM3"
$PN"3"45;
"APWM2"
$PN"4"52;
"APWM1"
$PN"5"51;
"BPWM1"
$PN"1"44;
"THPAD"
$PN"41"2;
%"GND"
"1","(-425,50)","0","mstr_symbols","I91";
;
SIZE"1B"
VOLTAGE"0.0V"
CDS_LIB"mstr_symbols"
BODY_TYPE"PLUMBING"
HDL_POWER"GND";
"A\NAC"18;
%"CAP_A"
"1","(-425,425)","2","dev_discrete","I92";
;
CDS_LOCATION"C9M11"
CDS_LIB"dev_discrete"
ROOM"VDDQ_KLM_PWR_VR"
CDS_SEC"1"
SEC_TYPE"0402V"
SEC"1"
MATERIAL"X7R"
VOLTAGE"16V"
PACK_TYPE"0402V"
TOLERANCE"10%"
VALUE"0.1UF"
PART_NUMBER"A36096-030"
LOCATION"C9M11";
"B"
$PN"2"18;
"A"
$PN"1"65;
END.
